# BASEBOARD_FAB2 (Tioga Pass) — schematic netlist excerpt (pin names and nets, part order shuffled) for the footprints in the layout excerpt that follows; sources: Cadence DE-HDL packaged netlist, KiCad conversion of Wiwynn_Tioga_Pass_MB.brd

C2D4  CAP_A  22.0UF 4V 20% X6S  pkg 0603V  page 228 : A = PVDDQ_KLM ; B = GND
R25W100  RES  4.75K 1% CHIP  pkg 0402  page 150 : A = P3V3_STBY ; B = GPIOS7
R25W94  RES  4.75K 1% CHIP  pkg 0402  page 137 : A = GND ; B = PD_SPI_BMC_BT_CS0_N

(kicad_pcb
	(version 20260206)
	(generator "pcbnew")
	(generator_version "10.0")
	(general
		(thickness 1.6)
		(legacy_teardrops no)
	)
	(paper "A4")
	(title_block
		(title "Wiwynn_Tioga_Pass_MB.brd")
		(comment 1 "Tioga Pass / footprints 759-761 of 4770")
	)
	(layers
		(0 "F.Cu" signal "TOP")
		(4 "In1.Cu" signal "L2GND")
		(6 "In2.Cu" signal "L3")
		(8 "In3.Cu" signal "L4GND")
		(10 "In4.Cu" signal "L5")
		(12 "In5.Cu" signal "L6GND")
		(14 "In6.Cu" signal "L7VCC")
		(16 "In7.Cu" signal "L8VCC")
		(18 "In8.Cu" signal "L9GND")
		(20 "In9.Cu" signal "L10")
		(22 "In10.Cu" signal "L11GND")
		(24 "In11.Cu" signal "L12")
		(26 "In12.Cu" signal "L13GND")
		(2 "B.Cu" signal "BOTTOM")
		(9 "F.Adhes" user "F.Adhesive")
		(11 "B.Adhes" user "B.Adhesive")
		(13 "F.Paste" user "Package Geometry/Pastemask Top")
		(15 "B.Paste" user "Package Geometry/Pastemask Bottom")
		(5 "F.SilkS" user "Ref Des/Silkscreen Top")
		(7 "B.SilkS" user "Ref Des/Silkscreen Bottom")
		(1 "F.Mask" user "Board Geometry/Soldermask Top")
		(3 "B.Mask" user "Board Geometry/Soldermask Bottom")
		(17 "Dwgs.User" user "User.Drawings")
		(19 "Cmts.User" user "User.Comments")
		(21 "Eco1.User" user "User.Eco1")
		(23 "Eco2.User" user "User.Eco2")
		(25 "Edge.Cuts" user "Board Geometry/Outline")
		(27 "Margin" user)
		(31 "F.CrtYd" user "Package Geometry/Place Bound Top")
		(29 "B.CrtYd" user "Package Geometry/Place Bound Bottom")
		(35 "F.Fab" user "Ref Des/Assembly Top")
		(33 "B.Fab" user "Ref Des/Assembly Bottom")
	)
	(footprint ""
		(layer "F.Cu")
		(at 447.3829 -40.2971 90)
		(property "Reference" "R25W94"
			(at -0.8382 -0.67818 90)
			(unlocked yes)
			(layer "F.SilkS")
			(effects
				(font
					(size 0.4064 0.254)
					(thickness 0.1524)
				)
				(justify left)
			)
		)
		(property "Value" ""
			(at 0 0 90)
			(layer "F.Fab")
			(effects
				(font
					(size 1.27 1.27)
				)
			)
		)
		(duplicate_pad_numbers_are_jumpers no)
		(fp_poly
			(pts
				(xy -0.2794 -0.1016) (xy 0.2794 -0.1016) (xy 0.2794 0.9906) (xy -0.2794 0.9906)
			)
			(stroke
				(width 0)
				(type default)
			)
			(fill no)
			(layer "F.CrtYd")
		)
		(fp_line
			(start 0.2794 -0.1016)
			(end -0.2794 -0.1016)
			(stroke
				(width 0.1)
				(type default)
			)
			(layer "F.Fab")
		)
		(fp_line
			(start -0.2794 -0.1016)
			(end -0.2794 0.9906)
			(stroke
				(width 0.1)
				(type default)
			)
			(layer "F.Fab")
		)
		(fp_line
			(start 0.2794 0.9906)
			(end 0.2794 -0.1016)
			(stroke
				(width 0.1)
				(type default)
			)
			(layer "F.Fab")
		)
		(fp_line
			(start -0.2794 0.9906)
			(end 0.2794 0.9906)
			(stroke
				(width 0.1)
				(type default)
			)
			(layer "F.Fab")
		)
		(pad "1" smd rect
			(at 0 0 90)
			(size 0.508 0.508)
			(layers "F.Cu" "F.Mask" "F.Paste")
			(net "GND")
		)
		(pad "2" smd rect
			(at 0 0.889 90)
			(size 0.508 0.508)
			(layers "F.Cu" "F.Mask" "F.Paste")
			(net "PD_SPI_BMC_BT_CS0_N")
		)
		(zone
			(layer "F.Cu")
			(hatch none 0.5)
			(connect_pads
				(clearance 0)
			)
			(min_thickness 0.25)
			(keepout
				(tracks allowed)
				(vias not_allowed)
				(pads allowed)
				(copperpour not_allowed)
				(footprints allowed)
			)
			(placement
				(enabled no)
				(sheetname "")
			)
			(fill
				(thermal_gap 0.5)
				(thermal_bridge_width 0.5)
				(island_removal_mode 0)
			)
			(polygon
				(pts
					(xy 447.6369 -40.0431) (xy 447.6369 -40.5511) (xy 448.0179 -40.5511) (xy 448.0179 -40.0431)
				)
			)
		)
		(zone
			(layer "F.Cu")
			(hatch none 0.5)
			(connect_pads
				(clearance 0)
			)
			(min_thickness 0.25)
			(keepout
				(tracks not_allowed)
				(vias allowed)
				(pads allowed)
				(copperpour not_allowed)
				(footprints allowed)
			)
			(placement
				(enabled no)
				(sheetname "")
			)
			(fill
				(thermal_gap 0.5)
				(thermal_bridge_width 0.5)
				(island_removal_mode 0)
			)
			(polygon
				(pts
					(xy 448.0179 -40.0431) (xy 448.0179 -40.5511) (xy 447.6369 -40.5511) (xy 447.6369 -40.0431)
				)
			)
		)
	)
	(footprint ""
		(layer "F.Cu")
		(at 425.919646 -48.968152)
		(property "Reference" "R25W100"
			(at -0.8382 -0.67818 0)
			(unlocked yes)
			(layer "F.SilkS")
			(effects
				(font
					(size 0.4064 0.254)
					(thickness 0.1524)
				)
				(justify left)
			)
		)
		(property "Value" ""
			(at 0 0 0)
			(layer "F.Fab")
			(effects
				(font
					(size 1.27 1.27)
				)
			)
		)
		(duplicate_pad_numbers_are_jumpers no)
		(fp_poly
			(pts
				(xy -0.2794 -0.1016) (xy 0.2794 -0.1016) (xy 0.2794 0.9906) (xy -0.2794 0.9906)
			)
			(stroke
				(width 0)
				(type default)
			)
			(fill no)
			(layer "F.CrtYd")
		)
		(fp_line
			(start -0.2794 -0.1016)
			(end -0.2794 0.9906)
			(stroke
				(width 0.1)
				(type default)
			)
			(layer "F.Fab")
		)
		(fp_line
			(start -0.2794 0.9906)
			(end 0.2794 0.9906)
			(stroke
				(width 0.1)
				(type default)
			)
			(layer "F.Fab")
		)
		(fp_line
			(start 0.2794 -0.1016)
			(end -0.2794 -0.1016)
			(stroke
				(width 0.1)
				(type default)
			)
			(layer "F.Fab")
		)
		(fp_line
			(start 0.2794 0.9906)
			(end 0.2794 -0.1016)
			(stroke
				(width 0.1)
				(type default)
			)
			(layer "F.Fab")
		)
		(pad "1" smd rect
			(at 0 0)
			(size 0.508 0.508)
			(layers "F.Cu" "F.Mask" "F.Paste")
			(net "P3V3_STBY")
		)
		(pad "2" smd rect
			(at 0 0.889)
			(size 0.508 0.508)
			(layers "F.Cu" "F.Mask" "F.Paste")
			(net "GPIOS7")
		)
		(zone
			(layer "F.Cu")
			(hatch none 0.5)
			(connect_pads
				(clearance 0)
			)
			(min_thickness 0.25)
			(keepout
				(tracks allowed)
				(vias not_allowed)
				(pads allowed)
				(copperpour not_allowed)
				(footprints allowed)
			)
			(placement
				(enabled no)
				(sheetname "")
			)
			(fill
				(thermal_gap 0.5)
				(thermal_bridge_width 0.5)
				(island_removal_mode 0)
			)
			(polygon
				(pts
					(xy 425.665646 -48.714152) (xy 426.173646 -48.714152) (xy 426.173646 -48.333152) (xy 425.665646 -48.333152)
				)
			)
		)
		(zone
			(layer "F.Cu")
			(hatch none 0.5)
			(connect_pads
				(clearance 0)
			)
			(min_thickness 0.25)
			(keepout
				(tracks not_allowed)
				(vias allowed)
				(pads allowed)
				(copperpour not_allowed)
				(footprints allowed)
			)
			(placement
				(enabled no)
				(sheetname "")
			)
			(fill
				(thermal_gap 0.5)
				(thermal_bridge_width 0.5)
				(island_removal_mode 0)
			)
			(polygon
				(pts
					(xy 425.665646 -48.333152) (xy 426.173646 -48.333152) (xy 426.173646 -48.714152) (xy 425.665646 -48.714152)
				)
			)
		)
	)
	(footprint ""
		(layer "F.Cu")
		(at 99.769168 -84.7598)
		(property "Reference" "C2D4"
			(at 0 0 0)
			(layer "F.SilkS")
			(hide yes)
			(effects
				(font
					(size 1.27 1.27)
				)
			)
		)
		(property "Value" ""
			(at 0 0 0)
			(layer "F.Fab")
			(effects
				(font
					(size 1.27 1.27)
				)
			)
		)
		(duplicate_pad_numbers_are_jumpers no)
		(fp_poly
			(pts
				(xy -0.4953 -0.2032) (xy 0.4953 -0.2032) (xy 0.4953 1.6002) (xy -0.4953 1.6002)
			)
			(stroke
				(width 0)
				(type default)
			)
			(fill no)
			(layer "F.CrtYd")
		)
		(fp_line
			(start -0.4953 -0.2032)
			(end 0.4953 -0.2032)
			(stroke
				(width 0.1)
				(type default)
			)
			(layer "F.Fab")
		)
		(fp_line
			(start -0.4953 1.6002)
			(end -0.4953 -0.2032)
			(stroke
				(width 0.1)
				(type default)
			)
			(layer "F.Fab")
		)
		(fp_line
			(start 0.4953 -0.2032)
			(end 0.4953 1.6002)
			(stroke
				(width 0.1)
				(type default)
			)
			(layer "F.Fab")
		)
		(fp_line
			(start 0.4953 1.6002)
			(end -0.4953 1.6002)
			(stroke
				(width 0.1)
				(type default)
			)
			(layer "F.Fab")
		)
		(pad "1" smd rect
			(at 0 0)
			(size 0.762 0.889)
			(layers "F.Cu" "F.Mask" "F.Paste")
			(net "PVDDQ_KLM")
		)
		(pad "2" smd rect
			(at 0 1.397)
			(size 0.762 0.889)
			(layers "F.Cu" "F.Mask" "F.Paste")
			(net "GND")
		)
		(zone
			(layer "F.Cu")
			(hatch none 0.5)
			(connect_pads
				(clearance 0)
			)
			(min_thickness 0.25)
			(keepout
				(tracks not_allowed)
				(vias allowed)
				(pads allowed)
				(copperpour not_allowed)
				(footprints allowed)
			)
			(placement
				(enabled no)
				(sheetname "")
			)
			(fill
				(thermal_gap 0.5)
				(thermal_bridge_width 0.5)
				(island_removal_mode 0)
			)
			(polygon
				(pts
					(xy 99.388168 -84.3153) (xy 100.150168 -84.3153) (xy 100.150168 -83.8073) (xy 99.388168 -83.8073)
				)
			)
		)
	)
)
